(kicad_pcb
	(version 20241229)
	(generator "pcbnew")
	(generator_version "9.0")
	(general
		(thickness 1.6296)
		(legacy_teardrops no)
	)
	(paper "A3")
	(title_block
		(title "Thunderbolt to 10GbE adapter")
		(date "2026-04-21")
		(rev "1.1.0")
		(company "Antmicro Ltd")
		(comment 1 "www.antmicro.com")
		(comment 9 "footprints 407-411 of 703")
	)
	(layers
		(0 "F.Cu" signal)
		(4 "In1.Cu" signal)
		(6 "In2.Cu" signal)
		(8 "In3.Cu" signal)
		(10 "In4.Cu" signal)
		(12 "In5.Cu" signal)
		(14 "In6.Cu" signal)
		(2 "B.Cu" signal)
		(9 "F.Adhes" user "F.Adhesive")
		(11 "B.Adhes" user "B.Adhesive")
		(13 "F.Paste" user)
		(15 "B.Paste" user)
		(5 "F.SilkS" user "F.Silkscreen")
		(7 "B.SilkS" user "B.Silkscreen")
		(1 "F.Mask" user)
		(3 "B.Mask" user)
		(17 "Dwgs.User" user "User.Drawings")
		(19 "Cmts.User" user "User.Comments")
		(21 "Eco1.User" user "User.Eco1")
		(23 "Eco2.User" user "User.Eco2")
		(25 "Edge.Cuts" user)
		(27 "Margin" user)
		(31 "F.CrtYd" user "F.Courtyard")
		(29 "B.CrtYd" user "B.Courtyard")
		(35 "F.Fab" user)
		(33 "B.Fab" user)
	)
	(footprint "antmicro-footprints:R_0402_1005Metric"
		(layer "B.Cu")
		(at 134.75 140.9 90)
		(descr "Resistor SMD 0402")
		(tags "resistor SMD 0402")
		(property "Reference" "R17"
			(at 9.557574 19.525001 270)
			(layer "B.SilkS")
			(effects
				(font
					(size 0.7 0.7)
					(thickness 0.15)
				)
				(justify mirror)
			)
		)
		(property "Value" "R_10k_0402"
			(at -1.011843 -1.772047 270)
			(layer "B.Fab")
			(effects
				(font
					(size 0.7 0.7)
					(thickness 0.15)
				)
				(justify left bottom mirror)
			)
		)
		(property "Datasheet" "https://www.bourns.com/docs/product-datasheets/cr.pdf"
			(at 0 0 270)
			(layer "B.Fab")
			(hide yes)
			(effects
				(font
					(size 1.27 1.27)
					(thickness 0.15)
				)
				(justify mirror)
			)
		)
		(property "Description" "SMD Chip Resistor, 10 kohm, ± 1%, 62.5 mW, 0402 [1005 Metric], Thick Film, General Purpose"
			(at 0 0 270)
			(layer "B.Fab")
			(hide yes)
			(effects
				(font
					(size 1.27 1.27)
					(thickness 0.15)
				)
				(justify mirror)
			)
		)
		(property "MPN" "CR0402-FX-1002GLF"
			(at 0 0 90)
			(unlocked yes)
			(layer "B.Fab")
			(hide yes)
			(effects
				(font
					(size 1 1)
					(thickness 0.15)
				)
				(justify mirror)
			)
		)
		(property "Manufacturer" "Bourns"
			(at 0 0 90)
			(unlocked yes)
			(layer "B.Fab")
			(hide yes)
			(effects
				(font
					(size 1 1)
					(thickness 0.15)
				)
				(justify mirror)
			)
		)
		(property "License" "Apache-2.0"
			(at 0 0 90)
			(unlocked yes)
			(layer "B.Fab")
			(hide yes)
			(effects
				(font
					(size 1 1)
					(thickness 0.15)
				)
				(justify mirror)
			)
		)
		(property "Val" "10k"
			(at 0 0 90)
			(unlocked yes)
			(layer "B.Fab")
			(hide yes)
			(effects
				(font
					(size 1 1)
					(thickness 0.15)
				)
				(justify mirror)
			)
		)
		(property "Tolerance" "1%"
			(at 0 0 90)
			(unlocked yes)
			(layer "B.Fab")
			(hide yes)
			(effects
				(font
					(size 1 1)
					(thickness 0.15)
				)
				(justify mirror)
			)
		)
		(property "Author" "Antmicro"
			(at 0 0 90)
			(unlocked yes)
			(layer "B.Fab")
			(hide yes)
			(effects
				(font
					(size 1 1)
					(thickness 0.15)
				)
				(justify mirror)
			)
		)
		(sheetname "/PD and TB DC-DC/")
		(sheetfile "PD_and_TB_DC_DC.kicad_sch")
		(attr smd)
		(fp_rect
			(start -0.925 0.47)
			(end 0.925 -0.47)
			(stroke
				(width 0.05)
				(type default)
			)
			(fill no)
			(layer "B.CrtYd")
		)
		(fp_rect
			(start -0.5 0.25)
			(end 0.5 -0.25)
			(stroke
				(width 0.15)
				(type solid)
			)
			(fill no)
			(layer "B.Fab")
		)
		(fp_text user "${REFERENCE}"
			(at -0.95 -3.168 270)
			(layer "B.Fab")
			(effects
				(font
					(size 0.7 0.7)
					(thickness 0.15)
				)
				(justify left bottom mirror)
			)
		)
		(fp_text user "License: Apache-2.0"
			(at -0.95 -5.169 270)
			(layer "B.Fab")
			(effects
				(font
					(size 0.7 0.7)
					(thickness 0.15)
				)
				(justify left bottom mirror)
			)
		)
		(fp_text user "Author: Antmicro"
			(at -0.95 -4.169 270)
			(layer "B.Fab")
			(effects
				(font
					(size 0.7 0.7)
					(thickness 0.15)
				)
				(justify left bottom mirror)
			)
		)
		(pad "1" smd roundrect
			(at -0.48 0 90)
			(size 0.59 0.64)
			(layers "B.Cu" "B.Mask" "B.Paste")
			(roundrect_rratio 0.25)
			(net 304 "/PD and TB DC-DC/TPS_3V3")
			(pintype "passive")
		)
		(pad "2" smd roundrect
			(at 0.48 0 90)
			(size 0.59 0.64)
			(layers "B.Cu" "B.Mask" "B.Paste")
			(roundrect_rratio 0.25)
			(net 203 "Net-(U3-GPIO6)")
			(pintype "passive")
		)
	)
	(footprint "antmicro-footprints:R_0402_1005Metric"
		(layer "B.Cu")
		(at 155.131866 70.035117 -90)
		(descr "Resistor SMD 0402")
		(tags "resistor SMD 0402")
		(property "Reference" "R168"
			(at 9.464883 -19.468134 90)
			(layer "B.SilkS")
			(effects
				(font
					(size 0.7 0.7)
					(thickness 0.15)
				)
				(justify mirror)
			)
		)
		(property "Value" "R_22R_0402"
			(at -1.011843 -1.772047 90)
			(layer "B.Fab")
			(effects
				(font
					(size 0.7 0.7)
					(thickness 0.15)
				)
				(justify left bottom mirror)
			)
		)
		(property "Datasheet" "https://www.bourns.com/docs/product-datasheets/cr.pdf"
			(at 0 0 90)
			(layer "B.Fab")
			(hide yes)
			(effects
				(font
					(size 1.27 1.27)
					(thickness 0.15)
				)
				(justify mirror)
			)
		)
		(property "Description" "SMD Chip Resistor, 22 ohm, ± 1%, 62.5 mW, 0402 [1005 Metric], Thick Film, General Purpose"
			(at 0 0 90)
			(layer "B.Fab")
			(hide yes)
			(effects
				(font
					(size 1.27 1.27)
					(thickness 0.15)
				)
				(justify mirror)
			)
		)
		(property "MPN" "CR0402-FX-22R0GLF"
			(at 0 0 270)
			(unlocked yes)
			(layer "B.Fab")
			(hide yes)
			(effects
				(font
					(size 1 1)
					(thickness 0.15)
				)
				(justify mirror)
			)
		)
		(property "Manufacturer" "Bourns"
			(at 0 0 270)
			(unlocked yes)
			(layer "B.Fab")
			(hide yes)
			(effects
				(font
					(size 1 1)
					(thickness 0.15)
				)
				(justify mirror)
			)
		)
		(property "License" "Apache-2.0"
			(at 0 0 270)
			(unlocked yes)
			(layer "B.Fab")
			(hide yes)
			(effects
				(font
					(size 1 1)
					(thickness 0.15)
				)
				(justify mirror)
			)
		)
		(property "Author" "Antmicro"
			(at 0 0 270)
			(unlocked yes)
			(layer "B.Fab")
			(hide yes)
			(effects
				(font
					(size 1 1)
					(thickness 0.15)
				)
				(justify mirror)
			)
		)
		(property "Val" "22R"
			(at 0 0 270)
			(unlocked yes)
			(layer "B.Fab")
			(hide yes)
			(effects
				(font
					(size 1 1)
					(thickness 0.15)
				)
				(justify mirror)
			)
		)
		(property "Tolerance" "1%"
			(at 0 0 270)
			(unlocked yes)
			(layer "B.Fab")
			(hide yes)
			(effects
				(font
					(size 1 1)
					(thickness 0.15)
				)
				(justify mirror)
			)
		)
		(sheetname "/X710-AT2 Misc/")
		(sheetfile "x710-at2-mics.kicad_sch")
		(attr smd)
		(fp_rect
			(start -0.925 0.47)
			(end 0.925 -0.47)
			(stroke
				(width 0.05)
				(type default)
			)
			(fill no)
			(layer "B.CrtYd")
		)
		(fp_rect
			(start -0.5 0.25)
			(end 0.5 -0.25)
			(stroke
				(width 0.15)
				(type solid)
			)
			(fill no)
			(layer "B.Fab")
		)
		(fp_text user "Author: Antmicro"
			(at -0.95 -4.169 90)
			(layer "B.Fab")
			(effects
				(font
					(size 0.7 0.7)
					(thickness 0.15)
				)
				(justify left bottom mirror)
			)
		)
		(fp_text user "License: Apache-2.0"
			(at -0.95 -5.169 90)
			(layer "B.Fab")
			(effects
				(font
					(size 0.7 0.7)
					(thickness 0.15)
				)
				(justify left bottom mirror)
			)
		)
		(fp_text user "${REFERENCE}"
			(at -0.95 -3.168 90)
			(layer "B.Fab")
			(effects
				(font
					(size 0.7 0.7)
					(thickness 0.15)
				)
				(justify left bottom mirror)
			)
		)
		(pad "1" smd roundrect
			(at -0.48 0 270)
			(size 0.59 0.64)
			(layers "B.Cu" "B.Mask" "B.Paste")
			(roundrect_rratio 0.25)
			(net 139 "/X710-AT2 Misc/NCSI.RXD_0")
			(pintype "passive")
		)
		(pad "2" smd roundrect
			(at 0.48 0 270)
			(size 0.59 0.64)
			(layers "B.Cu" "B.Mask" "B.Paste")
			(roundrect_rratio 0.25)
			(net 442 "Net-(U14D-NCSI_RXD_0)")
			(pintype "passive")
		)
	)
	(footprint "antmicro-footprints:R_0402_1005Metric"
		(layer "B.Cu")
		(at 140.399999 137.580998 180)
		(descr "Resistor SMD 0402")
		(tags "resistor SMD 0402")
		(property "Reference" "R14"
			(at -19.525001 8.1 0)
			(layer "B.SilkS")
			(effects
				(font
					(size 0.7 0.7)
					(thickness 0.15)
				)
				(justify mirror)
			)
		)
		(property "Value" "R_10k_0402"
			(at -1.011843 -1.772047 0)
			(layer "B.Fab")
			(effects
				(font
					(size 0.7 0.7)
					(thickness 0.15)
				)
				(justify left bottom mirror)
			)
		)
		(property "Datasheet" "https://www.bourns.com/docs/product-datasheets/cr.pdf"
			(at 0 0 0)
			(layer "B.Fab")
			(hide yes)
			(effects
				(font
					(size 1.27 1.27)
					(thickness 0.15)
				)
				(justify mirror)
			)
		)
		(property "Description" "SMD Chip Resistor, 10 kohm, ± 1%, 62.5 mW, 0402 [1005 Metric], Thick Film, General Purpose"
			(at 0 0 0)
			(layer "B.Fab")
			(hide yes)
			(effects
				(font
					(size 1.27 1.27)
					(thickness 0.15)
				)
				(justify mirror)
			)
		)
		(property "MPN" "CR0402-FX-1002GLF"
			(at 0 0 180)
			(unlocked yes)
			(layer "B.Fab")
			(hide yes)
			(effects
				(font
					(size 1 1)
					(thickness 0.15)
				)
				(justify mirror)
			)
		)
		(property "Manufacturer" "Bourns"
			(at 0 0 180)
			(unlocked yes)
			(layer "B.Fab")
			(hide yes)
			(effects
				(font
					(size 1 1)
					(thickness 0.15)
				)
				(justify mirror)
			)
		)
		(property "License" "Apache-2.0"
			(at 0 0 180)
			(unlocked yes)
			(layer "B.Fab")
			(hide yes)
			(effects
				(font
					(size 1 1)
					(thickness 0.15)
				)
				(justify mirror)
			)
		)
		(property "Val" "10k"
			(at 0 0 180)
			(unlocked yes)
			(layer "B.Fab")
			(hide yes)
			(effects
				(font
					(size 1 1)
					(thickness 0.15)
				)
				(justify mirror)
			)
		)
		(property "Tolerance" "1%"
			(at 0 0 180)
			(unlocked yes)
			(layer "B.Fab")
			(hide yes)
			(effects
				(font
					(size 1 1)
					(thickness 0.15)
				)
				(justify mirror)
			)
		)
		(property "Author" "Antmicro"
			(at 0 0 180)
			(unlocked yes)
			(layer "B.Fab")
			(hide yes)
			(effects
				(font
					(size 1 1)
					(thickness 0.15)
				)
				(justify mirror)
			)
		)
		(sheetname "/PD and TB DC-DC/")
		(sheetfile "PD_and_TB_DC_DC.kicad_sch")
		(attr smd)
		(fp_rect
			(start -0.925 0.47)
			(end 0.925 -0.47)
			(stroke
				(width 0.05)
				(type default)
			)
			(fill no)
			(layer "B.CrtYd")
		)
		(fp_rect
			(start -0.5 0.25)
			(end 0.5 -0.25)
			(stroke
				(width 0.15)
				(type solid)
			)
			(fill no)
			(layer "B.Fab")
		)
		(fp_text user "${REFERENCE}"
			(at -0.95 -3.168 0)
			(layer "B.Fab")
			(effects
				(font
					(size 0.7 0.7)
					(thickness 0.15)
				)
				(justify left bottom mirror)
			)
		)
		(fp_text user "License: Apache-2.0"
			(at -0.95 -5.169 0)
			(layer "B.Fab")
			(effects
				(font
					(size 0.7 0.7)
					(thickness 0.15)
				)
				(justify left bottom mirror)
			)
		)
		(fp_text user "Author: Antmicro"
			(at -0.95 -4.169 0)
			(layer "B.Fab")
			(effects
				(font
					(size 0.7 0.7)
					(thickness 0.15)
				)
				(justify left bottom mirror)
			)
		)
		(pad "1" smd roundrect
			(at -0.48 0 180)
			(size 0.59 0.64)
			(layers "B.Cu" "B.Mask" "B.Paste")
			(roundrect_rratio 0.25)
			(net 304 "/PD and TB DC-DC/TPS_3V3")
			(pintype "passive")
		)
		(pad "2" smd roundrect
			(at 0.48 0 180)
			(size 0.59 0.64)
			(layers "B.Cu" "B.Mask" "B.Paste")
			(roundrect_rratio 0.25)
			(net 200 "Net-(U3-I2C_IRQ2Z)")
			(pintype "passive")
		)
	)
	(footprint "antmicro-footprints:C_0402_1005Metric"
		(layer "B.Cu")
		(at 127.05 126.375)
		(descr "Capacitor SMD 0402")
		(tags "capacitor SMD 0402")
		(property "Reference" "C93"
			(at 21.900002 -7.700002 180)
			(layer "B.SilkS")
			(effects
				(font
					(size 0.7 0.7)
					(thickness 0.15)
				)
				(justify mirror)
			)
		)
		(property "Value" "C_1u_0402"
			(at -1.022927 -2.155213 180)
			(layer "B.Fab")
			(effects
				(font
					(size 0.7 0.7)
					(thickness 0.15)
				)
				(justify left bottom mirror)
			)
		)
		(property "Datasheet" "https://product.tdk.com/en/search/capacitor/ceramic/mlcc/info?part_no=C1005X6S1A105K050BC"
			(at 0 0 180)
			(layer "B.Fab")
			(hide yes)
			(effects
				(font
					(size 1.27 1.27)
					(thickness 0.15)
				)
				(justify mirror)
			)
		)
		(property "Description" "SMD Multilayer Ceramic Capacitor, 1 µF, 10 V, 0402 [1005 Metric], ± 10%, X6S, C"
			(at 0 0 180)
			(layer "B.Fab")
			(hide yes)
			(effects
				(font
					(size 1.27 1.27)
					(thickness 0.15)
				)
				(justify mirror)
			)
		)
		(property "MPN" "C1005X6S1A105K050BC"
			(at 0 0 0)
			(unlocked yes)
			(layer "B.Fab")
			(hide yes)
			(effects
				(font
					(size 1 1)
					(thickness 0.15)
				)
				(justify mirror)
			)
		)
		(property "Manufacturer" "TDK"
			(at 0 0 0)
			(unlocked yes)
			(layer "B.Fab")
			(hide yes)
			(effects
				(font
					(size 1 1)
					(thickness 0.15)
				)
				(justify mirror)
			)
		)
		(property "License" "Apache-2.0"
			(at 0 0 0)
			(unlocked yes)
			(layer "B.Fab")
			(hide yes)
			(effects
				(font
					(size 1 1)
					(thickness 0.15)
				)
				(justify mirror)
			)
		)
		(property "Val" "1u"
			(at 0 0 0)
			(unlocked yes)
			(layer "B.Fab")
			(hide yes)
			(effects
				(font
					(size 1 1)
					(thickness 0.15)
				)
				(justify mirror)
			)
		)
		(property "Voltage" ""
			(at 0 0 0)
			(unlocked yes)
			(layer "B.Fab")
			(hide yes)
			(effects
				(font
					(size 1 1)
					(thickness 0.15)
				)
				(justify mirror)
			)
		)
		(property "Dielectric" ""
			(at 0 0 0)
			(unlocked yes)
			(layer "B.Fab")
			(hide yes)
			(effects
				(font
					(size 1 1)
					(thickness 0.15)
				)
				(justify mirror)
			)
		)
		(property "Author" "Antmicro"
			(at 0 0 0)
			(unlocked yes)
			(layer "B.Fab")
			(hide yes)
			(effects
				(font
					(size 1 1)
					(thickness 0.15)
				)
				(justify mirror)
			)
		)
		(sheetname "/TB Controller - Power/")
		(sheetfile "tb-power.kicad_sch")
		(attr smd)
		(fp_rect
			(start -0.925 0.47)
			(end 0.925 -0.47)
			(stroke
				(width 0.05)
				(type default)
			)
			(fill no)
			(layer "B.CrtYd")
		)
		(fp_line
			(start -0.494 -0.248)
			(end -0.494 0.25)
			(stroke
				(width 0.15)
				(type solid)
			)
			(layer "B.Fab")
		)
		(fp_line
			(start -0.494 0.25)
			(end 0.504 0.25)
			(stroke
				(width 0.15)
				(type solid)
			)
			(layer "B.Fab")
		)
		(fp_line
			(start 0.504 -0.248)
			(end -0.494 -0.248)
			(stroke
				(width 0.15)
				(type solid)
			)
			(layer "B.Fab")
		)
		(fp_line
			(start 0.504 0.25)
			(end 0.504 -0.248)
			(stroke
				(width 0.15)
				(type solid)
			)
			(layer "B.Fab")
		)
		(fp_text user "License: Apache-2.0"
			(at -0.939 -5.799 180)
			(layer "B.Fab")
			(effects
				(font
					(size 0.7 0.7)
					(thickness 0.15)
				)
				(justify left bottom mirror)
			)
		)
		(fp_text user "${REFERENCE}"
			(at -0.939 -4.599 180)
			(layer "B.Fab")
			(effects
				(font
					(size 0.7 0.7)
					(thickness 0.15)
				)
				(justify left bottom mirror)
			)
		)
		(fp_text user "Author: Antmicro"
			(at -0.939 -3.399 180)
			(layer "B.Fab")
			(effects
				(font
					(size 0.7 0.7)
					(thickness 0.15)
				)
				(justify left bottom mirror)
			)
		)
		(pad "1" smd roundrect
			(at -0.48 0)
			(size 0.59 0.64)
			(layers "B.Cu" "B.Mask" "B.Paste")
			(roundrect_rratio 0.25)
			(net 23 "GND")
			(pintype "passive")
		)
		(pad "2" smd roundrect
			(at 0.48 0)
			(size 0.59 0.64)
			(layers "B.Cu" "B.Mask" "B.Paste")
			(roundrect_rratio 0.25)
			(net 68 "/TB Controller - Power/VCC_0P9")
			(pintype "passive")
		)
	)
	(footprint "antmicro-footprints:C_0402_1005Metric"
		(layer "B.Cu")
		(at 138.350001 134.599997)
		(descr "Capacitor SMD 0402")
		(tags "capacitor SMD 0402")
		(property "Reference" "C21"
			(at 19.525001 -8.1 180)
			(layer "B.SilkS")
			(effects
				(font
					(size 0.7 0.7)
					(thickness 0.15)
				)
				(justify mirror)
			)
		)
		(property "Value" "C_2u2_0402"
			(at -1.022927 -2.155213 180)
			(layer "B.Fab")
			(effects
				(font
					(size 0.7 0.7)
					(thickness 0.15)
				)
				(justify left bottom mirror)
			)
		)
		(property "Datasheet" "https://product.tdk.com/en/search/capacitor/ceramic/mlcc/info?part_no=C1005X5R1A225K050BC"
			(at 0 0 180)
			(layer "B.Fab")
			(hide yes)
			(effects
				(font
					(size 1.27 1.27)
					(thickness 0.15)
				)
				(justify mirror)
			)
		)
		(property "Description" "SMD Multilayer Ceramic Capacitor, 2.2 µF, 10 V, 0402 [1005 Metric], ± 10%, X5R, C"
			(at 0 0 180)
			(layer "B.Fab")
			(hide yes)
			(effects
				(font
					(size 1.27 1.27)
					(thickness 0.15)
				)
				(justify mirror)
			)
		)
		(property "MPN" "C1005X5R1A225K050BC"
			(at 0 0 0)
			(unlocked yes)
			(layer "B.Fab")
			(hide yes)
			(effects
				(font
					(size 1 1)
					(thickness 0.15)
				)
				(justify mirror)
			)
		)
		(property "Manufacturer" "TDK"
			(at 0 0 0)
			(unlocked yes)
			(layer "B.Fab")
			(hide yes)
			(effects
				(font
					(size 1 1)
					(thickness 0.15)
				)
				(justify mirror)
			)
		)
		(property "License" "Apache-2.0"
			(at 0 0 0)
			(unlocked yes)
			(layer "B.Fab")
			(hide yes)
			(effects
				(font
					(size 1 1)
					(thickness 0.15)
				)
				(justify mirror)
			)
		)
		(property "Val" "2u2"
			(at 0 0 0)
			(unlocked yes)
			(layer "B.Fab")
			(hide yes)
			(effects
				(font
					(size 1 1)
					(thickness 0.15)
				)
				(justify mirror)
			)
		)
		(property "Voltage" ""
			(at 0 0 0)
			(unlocked yes)
			(layer "B.Fab")
			(hide yes)
			(effects
				(font
					(size 1 1)
					(thickness 0.15)
				)
				(justify mirror)
			)
		)
		(property "Dielectric" ""
			(at 0 0 0)
			(unlocked yes)
			(layer "B.Fab")
			(hide yes)
			(effects
				(font
					(size 1 1)
					(thickness 0.15)
				)
				(justify mirror)
			)
		)
		(property "Author" "Antmicro"
			(at 0 0 0)
			(unlocked yes)
			(layer "B.Fab")
			(hide yes)
			(effects
				(font
					(size 1 1)
					(thickness 0.15)
				)
				(justify mirror)
			)
		)
		(sheetname "/PD and TB DC-DC/")
		(sheetfile "PD_and_TB_DC_DC.kicad_sch")
		(attr smd)
		(fp_rect
			(start -0.925 0.47)
			(end 0.925 -0.47)
			(stroke
				(width 0.05)
				(type default)
			)
			(fill no)
			(layer "B.CrtYd")
		)
		(fp_line
			(start -0.494 -0.248)
			(end -0.494 0.25)
			(stroke
				(width 0.15)
				(type solid)
			)
			(layer "B.Fab")
		)
		(fp_line
			(start -0.494 0.25)
			(end 0.504 0.25)
			(stroke
				(width 0.15)
				(type solid)
			)
			(layer "B.Fab")
		)
		(fp_line
			(start 0.504 -0.248)
			(end -0.494 -0.248)
			(stroke
				(width 0.15)
				(type solid)
			)
			(layer "B.Fab")
		)
		(fp_line
			(start 0.504 0.25)
			(end 0.504 -0.248)
			(stroke
				(width 0.15)
				(type solid)
			)
			(layer "B.Fab")
		)
		(fp_text user "${REFERENCE}"
			(at -0.939 -4.599 180)
			(layer "B.Fab")
			(effects
				(font
					(size 0.7 0.7)
					(thickness 0.15)
				)
				(justify left bottom mirror)
			)
		)
		(fp_text user "Author: Antmicro"
			(at -0.939 -3.399 180)
			(layer "B.Fab")
			(effects
				(font
					(size 0.7 0.7)
					(thickness 0.15)
				)
				(justify left bottom mirror)
			)
		)
		(fp_text user "License: Apache-2.0"
			(at -0.939 -5.799 180)
			(layer "B.Fab")
			(effects
				(font
					(size 0.7 0.7)
					(thickness 0.15)
				)
				(justify left bottom mirror)
			)
		)
		(pad "1" smd roundrect
			(at -0.48 0)
			(size 0.59 0.64)
			(layers "B.Cu" "B.Mask" "B.Paste")
			(roundrect_rratio 0.25)
			(net 175 "Net-(U3-LDO_1V8D)")
			(pintype "passive")
		)
		(pad "2" smd roundrect
			(at 0.48 0)
			(size 0.59 0.64)
			(layers "B.Cu" "B.Mask" "B.Paste")
			(roundrect_rratio 0.25)
			(net 23 "GND")
			(pintype "passive")
		)
	)
)
